(kicad_pcb
	(version 20260206)
	(generator "pcbnew")
	(generator_version "10.0")
	(general
		(thickness 1.6)
		(legacy_teardrops no)
	)
	(paper "A4")
	(title_block
		(title "03242023_DA0F0TMBIJ0_F0T_Motherboard_J_brd_V01_OCP.brd")
		(comment 1 "Grand Teton / footprints 5540-5545 of 6105")
	)
	(layers
		(0 "F.Cu" signal "TOP")
		(4 "In1.Cu" signal "GND")
		(6 "In2.Cu" signal "IN1")
		(8 "In3.Cu" signal "GND1")
		(10 "In4.Cu" signal "IN2")
		(12 "In5.Cu" signal "GND2")
		(14 "In6.Cu" signal "IN3")
		(16 "In7.Cu" signal "GND3")
		(18 "In8.Cu" signal "VCC")
		(20 "In9.Cu" signal "VCC1")
		(22 "In10.Cu" signal "GND4")
		(24 "In11.Cu" signal "IN4")
		(26 "In12.Cu" signal "GND5")
		(28 "In13.Cu" signal "IN5")
		(30 "In14.Cu" signal "GND6")
		(32 "In15.Cu" signal "IN6")
		(34 "In16.Cu" signal "GND7")
		(2 "B.Cu" signal "BOTTOM")
		(9 "F.Adhes" user "F.Adhesive")
		(11 "B.Adhes" user "B.Adhesive")
		(13 "F.Paste" user "Package Geometry/Pastemask Top")
		(15 "B.Paste" user "Package Geometry/Pastemask Bottom")
		(5 "F.SilkS" user "Ref Des/Silkscreen Top")
		(7 "B.SilkS" user "Ref Des/Silkscreen Bottom")
		(1 "F.Mask" user "Board Geometry/Soldermask Top")
		(3 "B.Mask" user "Board Geometry/Soldermask Bottom")
		(17 "Dwgs.User" user "User.Drawings")
		(19 "Cmts.User" user "User.Comments")
		(21 "Eco1.User" user "User.Eco1")
		(23 "Eco2.User" user "User.Eco2")
		(25 "Edge.Cuts" user "Board Geometry/Outline")
		(27 "Margin" user)
		(31 "F.CrtYd" user "Package Geometry/Place Bound Top")
		(29 "B.CrtYd" user "Package Geometry/Place Bound Bottom")
		(35 "F.Fab" user "Ref Des/Assembly Top")
		(33 "B.Fab" user "Ref Des/Assembly Bottom")
	)
	(footprint ""
		(layer "B.Cu")
		(at 295.699688 -367.164366 -90)
		(property "Reference" "PR1323"
			(at 0 0 90)
			(layer "B.SilkS")
			(hide yes)
			(effects
				(font
					(size 1.27 1.27)
				)
				(justify mirror)
			)
		)
		(property "Value" ""
			(at 0 0 90)
			(layer "B.Fab")
			(effects
				(font
					(size 1.27 1.27)
				)
				(justify mirror)
			)
		)
		(duplicate_pad_numbers_are_jumpers no)
		(fp_line
			(start -0.7874 0.4064)
			(end 0.7874 0.4064)
			(stroke
				(width 0.1524)
				(type default)
			)
			(layer "B.SilkS")
		)
		(fp_line
			(start 0.7874 0.4064)
			(end 0.7874 -0.4064)
			(stroke
				(width 0.1524)
				(type default)
			)
			(layer "B.SilkS")
		)
		(fp_line
			(start -0.7874 -0.4064)
			(end -0.7874 0.4064)
			(stroke
				(width 0.1524)
				(type default)
			)
			(layer "B.SilkS")
		)
		(fp_line
			(start 0.7874 -0.4064)
			(end -0.7874 -0.4064)
			(stroke
				(width 0.1524)
				(type default)
			)
			(layer "B.SilkS")
		)
		(fp_line
			(start -0.67945 0.3048)
			(end -0.120396 0.3048)
			(stroke
				(width 0.1)
				(type default)
			)
			(layer "B.Fab")
		)
		(fp_line
			(start -0.120396 0.3048)
			(end -0.120396 0.2794)
			(stroke
				(width 0.1)
				(type default)
			)
			(layer "B.Fab")
		)
		(fp_line
			(start 0.12065 0.3048)
			(end 0.67945 0.3048)
			(stroke
				(width 0.1)
				(type default)
			)
			(layer "B.Fab")
		)
		(fp_line
			(start 0.67945 0.3048)
			(end 0.67945 -0.305054)
			(stroke
				(width 0.1)
				(type default)
			)
			(layer "B.Fab")
		)
		(fp_line
			(start -0.120396 0.2794)
			(end 0.12065 0.2794)
			(stroke
				(width 0.1)
				(type default)
			)
			(layer "B.Fab")
		)
		(fp_line
			(start 0.12065 0.2794)
			(end 0.12065 0.3048)
			(stroke
				(width 0.1)
				(type default)
			)
			(layer "B.Fab")
		)
		(fp_line
			(start -0.12065 -0.2794)
			(end -0.12065 -0.3048)
			(stroke
				(width 0.1)
				(type default)
			)
			(layer "B.Fab")
		)
		(fp_line
			(start 0.12065 -0.2794)
			(end -0.12065 -0.2794)
			(stroke
				(width 0.1)
				(type default)
			)
			(layer "B.Fab")
		)
		(fp_line
			(start -0.67945 -0.3048)
			(end -0.67945 0.3048)
			(stroke
				(width 0.1)
				(type default)
			)
			(layer "B.Fab")
		)
		(fp_line
			(start -0.12065 -0.3048)
			(end -0.67945 -0.3048)
			(stroke
				(width 0.1)
				(type default)
			)
			(layer "B.Fab")
		)
		(fp_line
			(start 0.12065 -0.305054)
			(end 0.12065 -0.2794)
			(stroke
				(width 0.1)
				(type default)
			)
			(layer "B.Fab")
		)
		(fp_line
			(start 0.67945 -0.305054)
			(end 0.12065 -0.305054)
			(stroke
				(width 0.1)
				(type default)
			)
			(layer "B.Fab")
		)
		(pad "1" smd circle
			(at 0.40005 0 90)
			(size 0 0)
			(layers "B.Cu" "B.Mask" "B.Paste")
			(net "PVCCFA_EHV_FIVRA_CPU0_VOS2")
		)
		(pad "2" smd circle
			(at -0.40005 0 90)
			(size 0 0)
			(layers "B.Cu" "B.Mask" "B.Paste")
			(net "PVCCFA_EHV_FIVRA_CPU0")
		)
	)
	(footprint ""
		(layer "B.Cu")
		(at 133.5786 -28.6258 -90)
		(property "Reference" "R4636"
			(at 0 0 90)
			(layer "B.SilkS")
			(hide yes)
			(effects
				(font
					(size 1.27 1.27)
				)
				(justify mirror)
			)
		)
		(property "Value" ""
			(at 0 0 90)
			(layer "B.Fab")
			(effects
				(font
					(size 1.27 1.27)
				)
				(justify mirror)
			)
		)
		(duplicate_pad_numbers_are_jumpers no)
		(fp_line
			(start -0.7874 0.4064)
			(end 0.7874 0.4064)
			(stroke
				(width 0.1524)
				(type default)
			)
			(layer "B.SilkS")
		)
		(fp_line
			(start 0.7874 0.4064)
			(end 0.7874 -0.4064)
			(stroke
				(width 0.1524)
				(type default)
			)
			(layer "B.SilkS")
		)
		(fp_line
			(start -0.7874 -0.4064)
			(end -0.7874 0.4064)
			(stroke
				(width 0.1524)
				(type default)
			)
			(layer "B.SilkS")
		)
		(fp_line
			(start 0.7874 -0.4064)
			(end -0.7874 -0.4064)
			(stroke
				(width 0.1524)
				(type default)
			)
			(layer "B.SilkS")
		)
		(fp_line
			(start -0.67945 0.3048)
			(end -0.120396 0.3048)
			(stroke
				(width 0.1)
				(type default)
			)
			(layer "B.Fab")
		)
		(fp_line
			(start -0.120396 0.3048)
			(end -0.120396 0.2794)
			(stroke
				(width 0.1)
				(type default)
			)
			(layer "B.Fab")
		)
		(fp_line
			(start 0.12065 0.3048)
			(end 0.67945 0.3048)
			(stroke
				(width 0.1)
				(type default)
			)
			(layer "B.Fab")
		)
		(fp_line
			(start 0.67945 0.3048)
			(end 0.67945 -0.305054)
			(stroke
				(width 0.1)
				(type default)
			)
			(layer "B.Fab")
		)
		(fp_line
			(start -0.120396 0.2794)
			(end 0.12065 0.2794)
			(stroke
				(width 0.1)
				(type default)
			)
			(layer "B.Fab")
		)
		(fp_line
			(start 0.12065 0.2794)
			(end 0.12065 0.3048)
			(stroke
				(width 0.1)
				(type default)
			)
			(layer "B.Fab")
		)
		(fp_line
			(start -0.12065 -0.2794)
			(end -0.12065 -0.3048)
			(stroke
				(width 0.1)
				(type default)
			)
			(layer "B.Fab")
		)
		(fp_line
			(start 0.12065 -0.2794)
			(end -0.12065 -0.2794)
			(stroke
				(width 0.1)
				(type default)
			)
			(layer "B.Fab")
		)
		(fp_line
			(start -0.67945 -0.3048)
			(end -0.67945 0.3048)
			(stroke
				(width 0.1)
				(type default)
			)
			(layer "B.Fab")
		)
		(fp_line
			(start -0.12065 -0.3048)
			(end -0.67945 -0.3048)
			(stroke
				(width 0.1)
				(type default)
			)
			(layer "B.Fab")
		)
		(fp_line
			(start 0.12065 -0.305054)
			(end 0.12065 -0.2794)
			(stroke
				(width 0.1)
				(type default)
			)
			(layer "B.Fab")
		)
		(fp_line
			(start 0.67945 -0.305054)
			(end 0.12065 -0.305054)
			(stroke
				(width 0.1)
				(type default)
			)
			(layer "B.Fab")
		)
		(pad "1" smd circle
			(at 0.40005 0 90)
			(size 0 0)
			(layers "B.Cu" "B.Mask" "B.Paste")
			(net "USB3_PCH_RX_DP<4>")
		)
		(pad "2" smd circle
			(at -0.40005 0 90)
			(size 0 0)
			(layers "B.Cu" "B.Mask" "B.Paste")
			(net "GND")
		)
	)
	(footprint ""
		(layer "B.Cu")
		(at 317.902844 -31.523178 180)
		(property "Reference" "R1197"
			(at 0 0 0)
			(layer "B.SilkS")
			(hide yes)
			(effects
				(font
					(size 1.27 1.27)
				)
				(justify mirror)
			)
		)
		(property "Value" ""
			(at 0 0 0)
			(layer "B.Fab")
			(effects
				(font
					(size 1.27 1.27)
				)
				(justify mirror)
			)
		)
		(duplicate_pad_numbers_are_jumpers no)
		(fp_line
			(start 0.7874 0.4064)
			(end 0.7874 -0.4064)
			(stroke
				(width 0.1524)
				(type default)
			)
			(layer "B.SilkS")
		)
		(fp_line
			(start 0.7874 -0.4064)
			(end -0.7874 -0.4064)
			(stroke
				(width 0.1524)
				(type default)
			)
			(layer "B.SilkS")
		)
		(fp_line
			(start -0.7874 0.4064)
			(end 0.7874 0.4064)
			(stroke
				(width 0.1524)
				(type default)
			)
			(layer "B.SilkS")
		)
		(fp_line
			(start -0.7874 -0.4064)
			(end -0.7874 0.4064)
			(stroke
				(width 0.1524)
				(type default)
			)
			(layer "B.SilkS")
		)
		(fp_line
			(start 0.67945 0.3048)
			(end 0.67945 -0.305054)
			(stroke
				(width 0.1)
				(type default)
			)
			(layer "B.Fab")
		)
		(fp_line
			(start 0.67945 -0.305054)
			(end 0.12065 -0.305054)
			(stroke
				(width 0.1)
				(type default)
			)
			(layer "B.Fab")
		)
		(fp_line
			(start 0.12065 0.3048)
			(end 0.67945 0.3048)
			(stroke
				(width 0.1)
				(type default)
			)
			(layer "B.Fab")
		)
		(fp_line
			(start 0.12065 0.2794)
			(end 0.12065 0.3048)
			(stroke
				(width 0.1)
				(type default)
			)
			(layer "B.Fab")
		)
		(fp_line
			(start 0.12065 -0.2794)
			(end -0.12065 -0.2794)
			(stroke
				(width 0.1)
				(type default)
			)
			(layer "B.Fab")
		)
		(fp_line
			(start 0.12065 -0.305054)
			(end 0.12065 -0.2794)
			(stroke
				(width 0.1)
				(type default)
			)
			(layer "B.Fab")
		)
		(fp_line
			(start -0.120396 0.3048)
			(end -0.120396 0.2794)
			(stroke
				(width 0.1)
				(type default)
			)
			(layer "B.Fab")
		)
		(fp_line
			(start -0.120396 0.2794)
			(end 0.12065 0.2794)
			(stroke
				(width 0.1)
				(type default)
			)
			(layer "B.Fab")
		)
		(fp_line
			(start -0.12065 -0.2794)
			(end -0.12065 -0.3048)
			(stroke
				(width 0.1)
				(type default)
			)
			(layer "B.Fab")
		)
		(fp_line
			(start -0.12065 -0.3048)
			(end -0.67945 -0.3048)
			(stroke
				(width 0.1)
				(type default)
			)
			(layer "B.Fab")
		)
		(fp_line
			(start -0.67945 0.3048)
			(end -0.120396 0.3048)
			(stroke
				(width 0.1)
				(type default)
			)
			(layer "B.Fab")
		)
		(fp_line
			(start -0.67945 -0.3048)
			(end -0.67945 0.3048)
			(stroke
				(width 0.1)
				(type default)
			)
			(layer "B.Fab")
		)
		(pad "1" smd circle
			(at 0.40005 0)
			(size 0 0)
			(layers "B.Cu" "B.Mask" "B.Paste")
			(net "GND")
		)
		(pad "2" smd circle
			(at -0.40005 0)
			(size 0 0)
			(layers "B.Cu" "B.Mask" "B.Paste")
			(net "PD_SUSCLK")
		)
	)
	(footprint ""
		(layer "B.Cu")
		(at 455.66838 -382.435608)
		(property "Reference" "PR3337"
			(at 0 0 0)
			(layer "B.SilkS")
			(hide yes)
			(effects
				(font
					(size 1.27 1.27)
				)
				(justify mirror)
			)
		)
		(property "Value" ""
			(at 0 0 0)
			(layer "B.Fab")
			(effects
				(font
					(size 1.27 1.27)
				)
				(justify mirror)
			)
		)
		(duplicate_pad_numbers_are_jumpers no)
		(fp_line
			(start -0.7874 -0.4064)
			(end -0.7874 0.4064)
			(stroke
				(width 0.1524)
				(type default)
			)
			(layer "B.SilkS")
		)
		(fp_line
			(start -0.7874 0.4064)
			(end 0.7874 0.4064)
			(stroke
				(width 0.1524)
				(type default)
			)
			(layer "B.SilkS")
		)
		(fp_line
			(start 0.7874 -0.4064)
			(end -0.7874 -0.4064)
			(stroke
				(width 0.1524)
				(type default)
			)
			(layer "B.SilkS")
		)
		(fp_line
			(start 0.7874 0.4064)
			(end 0.7874 -0.4064)
			(stroke
				(width 0.1524)
				(type default)
			)
			(layer "B.SilkS")
		)
		(fp_line
			(start -0.67945 -0.3048)
			(end -0.67945 0.3048)
			(stroke
				(width 0.1)
				(type default)
			)
			(layer "B.Fab")
		)
		(fp_line
			(start -0.67945 0.3048)
			(end -0.120396 0.3048)
			(stroke
				(width 0.1)
				(type default)
			)
			(layer "B.Fab")
		)
		(fp_line
			(start -0.12065 -0.3048)
			(end -0.67945 -0.3048)
			(stroke
				(width 0.1)
				(type default)
			)
			(layer "B.Fab")
		)
		(fp_line
			(start -0.12065 -0.2794)
			(end -0.12065 -0.3048)
			(stroke
				(width 0.1)
				(type default)
			)
			(layer "B.Fab")
		)
		(fp_line
			(start -0.120396 0.2794)
			(end 0.12065 0.2794)
			(stroke
				(width 0.1)
				(type default)
			)
			(layer "B.Fab")
		)
		(fp_line
			(start -0.120396 0.3048)
			(end -0.120396 0.2794)
			(stroke
				(width 0.1)
				(type default)
			)
			(layer "B.Fab")
		)
		(fp_line
			(start 0.12065 -0.305054)
			(end 0.12065 -0.2794)
			(stroke
				(width 0.1)
				(type default)
			)
			(layer "B.Fab")
		)
		(fp_line
			(start 0.12065 -0.2794)
			(end -0.12065 -0.2794)
			(stroke
				(width 0.1)
				(type default)
			)
			(layer "B.Fab")
		)
		(fp_line
			(start 0.12065 0.2794)
			(end 0.12065 0.3048)
			(stroke
				(width 0.1)
				(type default)
			)
			(layer "B.Fab")
		)
		(fp_line
			(start 0.12065 0.3048)
			(end 0.67945 0.3048)
			(stroke
				(width 0.1)
				(type default)
			)
			(layer "B.Fab")
		)
		(fp_line
			(start 0.67945 -0.305054)
			(end 0.12065 -0.305054)
			(stroke
				(width 0.1)
				(type default)
			)
			(layer "B.Fab")
		)
		(fp_line
			(start 0.67945 0.3048)
			(end 0.67945 -0.305054)
			(stroke
				(width 0.1)
				(type default)
			)
			(layer "B.Fab")
		)
		(pad "1" smd circle
			(at 0.40005 0 180)
			(size 0 0)
			(layers "B.Cu" "B.Mask" "B.Paste")
			(net "P5V_AUX_MODE")
		)
		(pad "2" smd circle
			(at -0.40005 0 180)
			(size 0 0)
			(layers "B.Cu" "B.Mask" "B.Paste")
			(net "GND")
		)
	)
	(footprint ""
		(layer "B.Cu")
		(at 168.544494 -9.457944 -90)
		(property "Reference" "C2078"
			(at 0 0 90)
			(layer "B.SilkS")
			(hide yes)
			(effects
				(font
					(size 1.27 1.27)
				)
				(justify mirror)
			)
		)
		(property "Value" ""
			(at 0 0 90)
			(layer "B.Fab")
			(effects
				(font
					(size 1.27 1.27)
				)
				(justify mirror)
			)
		)
		(duplicate_pad_numbers_are_jumpers no)
		(fp_line
			(start -0.299974 0.150114)
			(end 0.299974 0.150114)
			(stroke
				(width 0.1)
				(type default)
			)
			(layer "B.Fab")
		)
		(fp_line
			(start 0.299974 0.150114)
			(end 0.299974 -0.150114)
			(stroke
				(width 0.1)
				(type default)
			)
			(layer "B.Fab")
		)
		(fp_line
			(start -0.299974 -0.150114)
			(end -0.299974 0.150114)
			(stroke
				(width 0.1)
				(type default)
			)
			(layer "B.Fab")
		)
		(fp_line
			(start 0.299974 -0.150114)
			(end -0.299974 -0.150114)
			(stroke
				(width 0.1)
				(type default)
			)
			(layer "B.Fab")
		)
		(pad "1" smd rect
			(at 0.2667 0 90)
			(size 0.3048 0.381)
			(layers "B.Cu" "B.Mask" "B.Paste")
			(net "P3E_PCH_BMC_TX_DN")
		)
		(pad "2" smd rect
			(at -0.2667 0 90)
			(size 0.3048 0.381)
			(layers "B.Cu" "B.Mask" "B.Paste")
			(net "P3E_PCH_BMC_TX_C_DN")
		)
		(zone
			(layer "In16.Cu")
			(hatch none 0.5)
			(connect_pads
				(clearance 0)
			)
			(min_thickness 0.25)
			(keepout
				(tracks not_allowed)
				(vias allowed)
				(pads allowed)
				(copperpour not_allowed)
				(footprints allowed)
			)
			(placement
				(enabled no)
				(sheetname "")
			)
			(fill
				(thermal_gap 0.5)
				(thermal_bridge_width 0.5)
				(island_removal_mode 0)
			)
			(polygon
				(pts
					(xy 168.303194 -9.521444) (xy 168.785794 -9.521444) (xy 168.785794 -9.927844) (xy 168.303194 -9.927844)
				)
			)
		)
		(zone
			(layer "In16.Cu")
			(hatch none 0.5)
			(connect_pads
				(clearance 0)
			)
			(min_thickness 0.25)
			(keepout
				(tracks not_allowed)
				(vias allowed)
				(pads allowed)
				(copperpour not_allowed)
				(footprints allowed)
			)
			(placement
				(enabled no)
				(sheetname "")
			)
			(fill
				(thermal_gap 0.5)
				(thermal_bridge_width 0.5)
				(island_removal_mode 0)
			)
			(polygon
				(pts
					(xy 168.303194 -8.988044) (xy 168.785794 -8.988044) (xy 168.785794 -9.394444) (xy 168.303194 -9.394444)
				)
			)
		)
	)
	(footprint ""
		(layer "B.Cu")
		(at 37.947346 -318.252856)
		(property "Reference" "R945"
			(at 0 0 0)
			(layer "B.SilkS")
			(hide yes)
			(effects
				(font
					(size 1.27 1.27)
				)
				(justify mirror)
			)
		)
		(property "Value" ""
			(at 0 0 0)
			(layer "B.Fab")
			(effects
				(font
					(size 1.27 1.27)
				)
				(justify mirror)
			)
		)
		(duplicate_pad_numbers_are_jumpers no)
		(fp_line
			(start -0.7874 -0.4064)
			(end -0.7874 0.4064)
			(stroke
				(width 0.1524)
				(type default)
			)
			(layer "B.SilkS")
		)
		(fp_line
			(start -0.7874 0.4064)
			(end 0.7874 0.4064)
			(stroke
				(width 0.1524)
				(type default)
			)
			(layer "B.SilkS")
		)
		(fp_line
			(start 0.7874 -0.4064)
			(end -0.7874 -0.4064)
			(stroke
				(width 0.1524)
				(type default)
			)
			(layer "B.SilkS")
		)
		(fp_line
			(start 0.7874 0.4064)
			(end 0.7874 -0.4064)
			(stroke
				(width 0.1524)
				(type default)
			)
			(layer "B.SilkS")
		)
		(fp_line
			(start -0.67945 -0.3048)
			(end -0.67945 0.3048)
			(stroke
				(width 0.1)
				(type default)
			)
			(layer "B.Fab")
		)
		(fp_line
			(start -0.67945 0.3048)
			(end -0.120396 0.3048)
			(stroke
				(width 0.1)
				(type default)
			)
			(layer "B.Fab")
		)
		(fp_line
			(start -0.12065 -0.3048)
			(end -0.67945 -0.3048)
			(stroke
				(width 0.1)
				(type default)
			)
			(layer "B.Fab")
		)
		(fp_line
			(start -0.12065 -0.2794)
			(end -0.12065 -0.3048)
			(stroke
				(width 0.1)
				(type default)
			)
			(layer "B.Fab")
		)
		(fp_line
			(start -0.120396 0.2794)
			(end 0.12065 0.2794)
			(stroke
				(width 0.1)
				(type default)
			)
			(layer "B.Fab")
		)
		(fp_line
			(start -0.120396 0.3048)
			(end -0.120396 0.2794)
			(stroke
				(width 0.1)
				(type default)
			)
			(layer "B.Fab")
		)
		(fp_line
			(start 0.12065 -0.305054)
			(end 0.12065 -0.2794)
			(stroke
				(width 0.1)
				(type default)
			)
			(layer "B.Fab")
		)
		(fp_line
			(start 0.12065 -0.2794)
			(end -0.12065 -0.2794)
			(stroke
				(width 0.1)
				(type default)
			)
			(layer "B.Fab")
		)
		(fp_line
			(start 0.12065 0.2794)
			(end 0.12065 0.3048)
			(stroke
				(width 0.1)
				(type default)
			)
			(layer "B.Fab")
		)
		(fp_line
			(start 0.12065 0.3048)
			(end 0.67945 0.3048)
			(stroke
				(width 0.1)
				(type default)
			)
			(layer "B.Fab")
		)
		(fp_line
			(start 0.67945 -0.305054)
			(end 0.12065 -0.305054)
			(stroke
				(width 0.1)
				(type default)
			)
			(layer "B.Fab")
		)
		(fp_line
			(start 0.67945 0.3048)
			(end 0.67945 -0.305054)
			(stroke
				(width 0.1)
				(type default)
			)
			(layer "B.Fab")
		)
		(pad "1" smd circle
			(at 0.40005 0 180)
			(size 0 0)
			(layers "B.Cu" "B.Mask" "B.Paste")
			(net "P3V3_AUX")
		)
		(pad "2" smd circle
			(at -0.40005 0 180)
			(size 0 0)
			(layers "B.Cu" "B.Mask" "B.Paste")
			(net "PWRGD_FAIL_CPU1_CD_R1")
		)
	)
)
